# T6G (Grand Teton) — schematic netlist excerpt (pin names and nets, part order shuffled) for the footprints in the layout excerpt that follows; sources: Cadence DE-HDL packaged netlist, KiCad conversion of 04192023_DAF0TMB3IC0_F0TG_MB_C_brd_V02_OCP.brd

R943  Q_RES  4.7K 5% CHIP  pkg 0402LF  page 34 : A = P1V8_AUX ; B = FM_BIOS_POST_CMPLT_BUF_R1_N
C580  Q_CAP  0.1UF 10V 10% X7S  pkg C0201  page 279 : A = P0V9_CPU0_RT0_2A ; B = GND
C6689  Q_CAP_DIFFBUS  DIFF BUS_0.22UF 6.3V 20% X6S  pkg C0201  page 330 : \1\ = P5E_CPU1_P1_TX_BUF_C_DP<14> ; \2\ = P5E_CPU1_P1_TX_BUF_DP<14>

(kicad_pcb
	(version 20260206)
	(generator "pcbnew")
	(generator_version "10.0")
	(general
		(thickness 1.6)
		(legacy_teardrops no)
	)
	(paper "A4")
	(title_block
		(title "04192023_DAF0TMB3IC0_F0TG_MB_C_brd_V02_OCP.brd")
		(comment 1 "Grand Teton / footprints 6578-6580 of 8354")
	)
	(layers
		(0 "F.Cu" signal "TOP")
		(4 "In1.Cu" signal "GND")
		(6 "In2.Cu" signal "IN1")
		(8 "In3.Cu" signal "GND1")
		(10 "In4.Cu" signal "IN2")
		(12 "In5.Cu" signal "GND2")
		(14 "In6.Cu" signal "IN3")
		(16 "In7.Cu" signal "GND3")
		(18 "In8.Cu" signal "VCC")
		(20 "In9.Cu" signal "VCC1")
		(22 "In10.Cu" signal "GND4")
		(24 "In11.Cu" signal "IN4")
		(26 "In12.Cu" signal "GND5")
		(28 "In13.Cu" signal "IN5")
		(30 "In14.Cu" signal "GND6")
		(32 "In15.Cu" signal "IN6")
		(34 "In16.Cu" signal "GND7")
		(2 "B.Cu" signal "BOTTOM")
		(9 "F.Adhes" user "F.Adhesive")
		(11 "B.Adhes" user "B.Adhesive")
		(13 "F.Paste" user "Package Geometry/Pastemask Top")
		(15 "B.Paste" user "Package Geometry/Pastemask Bottom")
		(5 "F.SilkS" user "Ref Des/Silkscreen Top")
		(7 "B.SilkS" user "Ref Des/Silkscreen Bottom")
		(1 "F.Mask" user "Board Geometry/Soldermask Top")
		(3 "B.Mask" user "Board Geometry/Soldermask Bottom")
		(17 "Dwgs.User" user "User.Drawings")
		(19 "Cmts.User" user "User.Comments")
		(21 "Eco1.User" user "User.Eco1")
		(23 "Eco2.User" user "User.Eco2")
		(25 "Edge.Cuts" user "Board Geometry/Outline")
		(27 "Margin" user)
		(31 "F.CrtYd" user "Package Geometry/Place Bound Top")
		(29 "B.CrtYd" user "Package Geometry/Place Bound Bottom")
		(35 "F.Fab" user "Ref Des/Assembly Top")
		(33 "B.Fab" user "Ref Des/Assembly Bottom")
	)
	(footprint ""
		(layer "B.Cu")
		(at 303.518316 -396.393162 -90)
		(property "Reference" "C580"
			(at 0 0 90)
			(layer "B.SilkS")
			(hide yes)
			(effects
				(font
					(size 1.27 1.27)
				)
				(justify mirror)
			)
		)
		(property "Value" ""
			(at 0 0 90)
			(layer "B.Fab")
			(effects
				(font
					(size 1.27 1.27)
				)
				(justify mirror)
			)
		)
		(duplicate_pad_numbers_are_jumpers no)
		(fp_line
			(start -0.299974 0.150114)
			(end 0.299974 0.150114)
			(stroke
				(width 0.1)
				(type default)
			)
			(layer "B.Fab")
		)
		(fp_line
			(start 0.299974 0.150114)
			(end 0.299974 -0.150114)
			(stroke
				(width 0.1)
				(type default)
			)
			(layer "B.Fab")
		)
		(fp_line
			(start -0.299974 -0.150114)
			(end -0.299974 0.150114)
			(stroke
				(width 0.1)
				(type default)
			)
			(layer "B.Fab")
		)
		(fp_line
			(start 0.299974 -0.150114)
			(end -0.299974 -0.150114)
			(stroke
				(width 0.1)
				(type default)
			)
			(layer "B.Fab")
		)
		(pad "1" smd rect
			(at 0.2667 0 90)
			(size 0.3048 0.381)
			(layers "B.Cu" "B.Mask" "B.Paste")
			(net "P0V9_CPU0_RT0_2A")
		)
		(pad "2" smd rect
			(at -0.2667 0 90)
			(size 0.3048 0.381)
			(layers "B.Cu" "B.Mask" "B.Paste")
			(net "GND")
		)
	)
	(footprint ""
		(layer "B.Cu")
		(at 401.554696 -342.950292 -90)
		(property "Reference" "R943"
			(at 0 0 90)
			(layer "B.SilkS")
			(hide yes)
			(effects
				(font
					(size 1.27 1.27)
				)
				(justify mirror)
			)
		)
		(property "Value" ""
			(at 0 0 90)
			(layer "B.Fab")
			(effects
				(font
					(size 1.27 1.27)
				)
				(justify mirror)
			)
		)
		(duplicate_pad_numbers_are_jumpers no)
		(fp_line
			(start -0.7874 0.4064)
			(end 0.7874 0.4064)
			(stroke
				(width 0.1524)
				(type default)
			)
			(layer "B.SilkS")
		)
		(fp_line
			(start 0.7874 0.4064)
			(end 0.7874 -0.4064)
			(stroke
				(width 0.1524)
				(type default)
			)
			(layer "B.SilkS")
		)
		(fp_line
			(start -0.7874 -0.4064)
			(end -0.7874 0.4064)
			(stroke
				(width 0.1524)
				(type default)
			)
			(layer "B.SilkS")
		)
		(fp_line
			(start 0.7874 -0.4064)
			(end -0.7874 -0.4064)
			(stroke
				(width 0.1524)
				(type default)
			)
			(layer "B.SilkS")
		)
		(fp_line
			(start -0.67945 0.3048)
			(end -0.120396 0.3048)
			(stroke
				(width 0.1)
				(type default)
			)
			(layer "B.Fab")
		)
		(fp_line
			(start -0.120396 0.3048)
			(end -0.120396 0.2794)
			(stroke
				(width 0.1)
				(type default)
			)
			(layer "B.Fab")
		)
		(fp_line
			(start 0.12065 0.3048)
			(end 0.67945 0.3048)
			(stroke
				(width 0.1)
				(type default)
			)
			(layer "B.Fab")
		)
		(fp_line
			(start 0.67945 0.3048)
			(end 0.67945 -0.305054)
			(stroke
				(width 0.1)
				(type default)
			)
			(layer "B.Fab")
		)
		(fp_line
			(start -0.120396 0.2794)
			(end 0.12065 0.2794)
			(stroke
				(width 0.1)
				(type default)
			)
			(layer "B.Fab")
		)
		(fp_line
			(start 0.12065 0.2794)
			(end 0.12065 0.3048)
			(stroke
				(width 0.1)
				(type default)
			)
			(layer "B.Fab")
		)
		(fp_line
			(start -0.12065 -0.2794)
			(end -0.12065 -0.3048)
			(stroke
				(width 0.1)
				(type default)
			)
			(layer "B.Fab")
		)
		(fp_line
			(start 0.12065 -0.2794)
			(end -0.12065 -0.2794)
			(stroke
				(width 0.1)
				(type default)
			)
			(layer "B.Fab")
		)
		(fp_line
			(start -0.67945 -0.3048)
			(end -0.67945 0.3048)
			(stroke
				(width 0.1)
				(type default)
			)
			(layer "B.Fab")
		)
		(fp_line
			(start -0.12065 -0.3048)
			(end -0.67945 -0.3048)
			(stroke
				(width 0.1)
				(type default)
			)
			(layer "B.Fab")
		)
		(fp_line
			(start 0.12065 -0.305054)
			(end 0.12065 -0.2794)
			(stroke
				(width 0.1)
				(type default)
			)
			(layer "B.Fab")
		)
		(fp_line
			(start 0.67945 -0.305054)
			(end 0.12065 -0.305054)
			(stroke
				(width 0.1)
				(type default)
			)
			(layer "B.Fab")
		)
		(pad "1" smd circle
			(at 0.40005 0 90)
			(size 0 0)
			(layers "B.Cu" "B.Mask" "B.Paste")
			(net "P1V8_AUX")
		)
		(pad "2" smd circle
			(at -0.40005 0 90)
			(size 0 0)
			(layers "B.Cu" "B.Mask" "B.Paste")
			(net "FM_BIOS_POST_CMPLT_BUF_R1_N")
		)
	)
	(footprint ""
		(layer "B.Cu")
		(at 93.100144 -408.517344 90)
		(property "Reference" "C6689"
			(at 0 0 90)
			(layer "B.SilkS")
			(hide yes)
			(effects
				(font
					(size 1.27 1.27)
				)
				(justify mirror)
			)
		)
		(property "Value" ""
			(at 0 0 90)
			(layer "B.Fab")
			(effects
				(font
					(size 1.27 1.27)
				)
				(justify mirror)
			)
		)
		(duplicate_pad_numbers_are_jumpers no)
		(fp_line
			(start 0.299974 -0.150114)
			(end -0.299974 -0.150114)
			(stroke
				(width 0.1)
				(type default)
			)
			(layer "B.Fab")
		)
		(fp_line
			(start -0.299974 -0.150114)
			(end -0.299974 0.150114)
			(stroke
				(width 0.1)
				(type default)
			)
			(layer "B.Fab")
		)
		(fp_line
			(start 0.299974 0.150114)
			(end 0.299974 -0.150114)
			(stroke
				(width 0.1)
				(type default)
			)
			(layer "B.Fab")
		)
		(fp_line
			(start -0.299974 0.150114)
			(end 0.299974 0.150114)
			(stroke
				(width 0.1)
				(type default)
			)
			(layer "B.Fab")
		)
		(pad "1" smd rect
			(at 0.2667 0 270)
			(size 0.3048 0.381)
			(layers "B.Cu" "B.Mask" "B.Paste")
			(net "P5E_CPU1_P1_TX_BUF_C_DP<14>")
		)
		(pad "2" smd rect
			(at -0.2667 0 270)
			(size 0.3048 0.381)
			(layers "B.Cu" "B.Mask" "B.Paste")
			(net "P5E_CPU1_P1_TX_BUF_DP<14>")
		)
	)
)
